# T6G (Grand Teton) — schematic netlist excerpt (pin names and nets, part order shuffled) for the footprints in the layout excerpt that follows; sources: Cadence DE-HDL packaged netlist, KiCad conversion of 04192023_DAF0TMB3IC0_F0TG_MB_C_brd_V02_OCP.brd

PC123  Q_CAP  22UF 16V 20% X6S  pkg C0805  page 192 : A = SW_P12V_AUX_PVDD_33_S5_FLT ; B = GND
PC107  Q_CAP  0.1UF 25V 10% X7R  pkg 0402  page 205 : A = PVDDIO_P0 ; B = GND
PR181  Q_RES  0 5% CHIP  pkg 0402LF  page 210 : A = P12V_AUX ; B = PVDDCR_CPU0_P1_VINSEN

(kicad_pcb
	(version 20260206)
	(generator "pcbnew")
	(generator_version "10.0")
	(general
		(thickness 1.6)
		(legacy_teardrops no)
	)
	(paper "A4")
	(title_block
		(title "04192023_DAF0TMB3IC0_F0TG_MB_C_brd_V02_OCP.brd")
		(comment 1 "Grand Teton / footprints 3334-3336 of 8354")
	)
	(layers
		(0 "F.Cu" signal "TOP")
		(4 "In1.Cu" signal "GND")
		(6 "In2.Cu" signal "IN1")
		(8 "In3.Cu" signal "GND1")
		(10 "In4.Cu" signal "IN2")
		(12 "In5.Cu" signal "GND2")
		(14 "In6.Cu" signal "IN3")
		(16 "In7.Cu" signal "GND3")
		(18 "In8.Cu" signal "VCC")
		(20 "In9.Cu" signal "VCC1")
		(22 "In10.Cu" signal "GND4")
		(24 "In11.Cu" signal "IN4")
		(26 "In12.Cu" signal "GND5")
		(28 "In13.Cu" signal "IN5")
		(30 "In14.Cu" signal "GND6")
		(32 "In15.Cu" signal "IN6")
		(34 "In16.Cu" signal "GND7")
		(2 "B.Cu" signal "BOTTOM")
		(9 "F.Adhes" user "F.Adhesive")
		(11 "B.Adhes" user "B.Adhesive")
		(13 "F.Paste" user "Package Geometry/Pastemask Top")
		(15 "B.Paste" user "Package Geometry/Pastemask Bottom")
		(5 "F.SilkS" user "Ref Des/Silkscreen Top")
		(7 "B.SilkS" user "Ref Des/Silkscreen Bottom")
		(1 "F.Mask" user "Board Geometry/Soldermask Top")
		(3 "B.Mask" user "Board Geometry/Soldermask Bottom")
		(17 "Dwgs.User" user "User.Drawings")
		(19 "Cmts.User" user "User.Comments")
		(21 "Eco1.User" user "User.Eco1")
		(23 "Eco2.User" user "User.Eco2")
		(25 "Edge.Cuts" user "Board Geometry/Outline")
		(27 "Margin" user)
		(31 "F.CrtYd" user "Package Geometry/Place Bound Top")
		(29 "B.CrtYd" user "Package Geometry/Place Bound Bottom")
		(35 "F.Fab" user "Ref Des/Assembly Top")
		(33 "B.Fab" user "Ref Des/Assembly Bottom")
	)
	(footprint ""
		(layer "F.Cu")
		(at 101.948234 -141.20241 180)
		(property "Reference" "PR181"
			(at 0 0 180)
			(layer "F.SilkS")
			(hide yes)
			(effects
				(font
					(size 1.27 1.27)
				)
			)
		)
		(property "Value" ""
			(at 0 0 180)
			(layer "F.Fab")
			(effects
				(font
					(size 1.27 1.27)
				)
			)
		)
		(duplicate_pad_numbers_are_jumpers no)
		(fp_line
			(start 0.7874 0.4064)
			(end -0.7874 0.4064)
			(stroke
				(width 0.1524)
				(type default)
			)
			(layer "F.SilkS")
		)
		(fp_line
			(start 0.7874 -0.4064)
			(end 0.7874 0.4064)
			(stroke
				(width 0.1524)
				(type default)
			)
			(layer "F.SilkS")
		)
		(fp_line
			(start -0.7874 0.4064)
			(end -0.7874 -0.4064)
			(stroke
				(width 0.1524)
				(type default)
			)
			(layer "F.SilkS")
		)
		(fp_line
			(start -0.7874 -0.4064)
			(end 0.7874 -0.4064)
			(stroke
				(width 0.1524)
				(type default)
			)
			(layer "F.SilkS")
		)
		(fp_line
			(start 0.67945 0.3048)
			(end 0.120396 0.3048)
			(stroke
				(width 0.1)
				(type default)
			)
			(layer "F.Fab")
		)
		(fp_line
			(start 0.67945 -0.3048)
			(end 0.67945 0.3048)
			(stroke
				(width 0.1)
				(type default)
			)
			(layer "F.Fab")
		)
		(fp_line
			(start 0.12065 -0.2794)
			(end 0.12065 -0.3048)
			(stroke
				(width 0.1)
				(type default)
			)
			(layer "F.Fab")
		)
		(fp_line
			(start 0.12065 -0.3048)
			(end 0.67945 -0.3048)
			(stroke
				(width 0.1)
				(type default)
			)
			(layer "F.Fab")
		)
		(fp_line
			(start 0.120396 0.3048)
			(end 0.120396 0.2794)
			(stroke
				(width 0.1)
				(type default)
			)
			(layer "F.Fab")
		)
		(fp_line
			(start 0.120396 0.2794)
			(end -0.12065 0.2794)
			(stroke
				(width 0.1)
				(type default)
			)
			(layer "F.Fab")
		)
		(fp_line
			(start -0.12065 0.3048)
			(end -0.67945 0.3048)
			(stroke
				(width 0.1)
				(type default)
			)
			(layer "F.Fab")
		)
		(fp_line
			(start -0.12065 0.2794)
			(end -0.12065 0.3048)
			(stroke
				(width 0.1)
				(type default)
			)
			(layer "F.Fab")
		)
		(fp_line
			(start -0.12065 -0.2794)
			(end 0.12065 -0.2794)
			(stroke
				(width 0.1)
				(type default)
			)
			(layer "F.Fab")
		)
		(fp_line
			(start -0.12065 -0.305054)
			(end -0.12065 -0.2794)
			(stroke
				(width 0.1)
				(type default)
			)
			(layer "F.Fab")
		)
		(fp_line
			(start -0.67945 0.3048)
			(end -0.67945 -0.305054)
			(stroke
				(width 0.1)
				(type default)
			)
			(layer "F.Fab")
		)
		(fp_line
			(start -0.67945 -0.305054)
			(end -0.12065 -0.305054)
			(stroke
				(width 0.1)
				(type default)
			)
			(layer "F.Fab")
		)
		(pad "1" smd circle
			(at -0.40005 0 180)
			(size 0 0)
			(layers "F.Cu" "F.Mask" "F.Paste")
			(net "P12V_AUX")
		)
		(pad "2" smd circle
			(at 0.40005 0 180)
			(size 0 0)
			(layers "F.Cu" "F.Mask" "F.Paste")
			(net "PVDDCR_CPU0_P1_VINSEN")
		)
	)
	(footprint ""
		(layer "F.Cu")
		(at 203.573126 -344.92692)
		(property "Reference" "PC123"
			(at 0 0 0)
			(layer "F.SilkS")
			(hide yes)
			(effects
				(font
					(size 1.27 1.27)
				)
			)
		)
		(property "Value" ""
			(at 0 0 0)
			(layer "F.Fab")
			(effects
				(font
					(size 1.27 1.27)
				)
			)
		)
		(duplicate_pad_numbers_are_jumpers no)
		(fp_line
			(start -1.524 -0.762)
			(end 1.524 -0.762)
			(stroke
				(width 0.1524)
				(type default)
			)
			(layer "F.SilkS")
		)
		(fp_line
			(start -1.524 0.762)
			(end -1.524 -0.762)
			(stroke
				(width 0.1524)
				(type default)
			)
			(layer "F.SilkS")
		)
		(fp_line
			(start 1.524 -0.762)
			(end 1.524 0.762)
			(stroke
				(width 0.1524)
				(type default)
			)
			(layer "F.SilkS")
		)
		(fp_line
			(start 1.524 0.762)
			(end -1.524 0.762)
			(stroke
				(width 0.1524)
				(type default)
			)
			(layer "F.SilkS")
		)
		(fp_line
			(start -1.1049 -0.724916)
			(end -1.1049 0.724916)
			(stroke
				(width 0.1)
				(type default)
			)
			(layer "F.Fab")
		)
		(fp_line
			(start -1.1049 0.724916)
			(end 1.1049 0.724916)
			(stroke
				(width 0.1)
				(type default)
			)
			(layer "F.Fab")
		)
		(fp_line
			(start 1.1049 -0.724916)
			(end -1.1049 -0.724916)
			(stroke
				(width 0.1)
				(type default)
			)
			(layer "F.Fab")
		)
		(fp_line
			(start 1.1049 0.724916)
			(end 1.1049 -0.724916)
			(stroke
				(width 0.1)
				(type default)
			)
			(layer "F.Fab")
		)
		(pad "1" smd rect
			(at -0.889 0 180)
			(size 1.016 1.27)
			(layers "F.Cu" "F.Mask" "F.Paste")
			(net "SW_P12V_AUX_PVDD_33_S5_FLT")
		)
		(pad "2" smd rect
			(at 0.889 0 180)
			(size 1.016 1.27)
			(layers "F.Cu" "F.Mask" "F.Paste")
			(net "GND")
		)
	)
	(footprint ""
		(layer "F.Cu")
		(at 270.48841 -332.609952 90)
		(property "Reference" "PC107"
			(at 0 0 90)
			(layer "F.SilkS")
			(hide yes)
			(effects
				(font
					(size 1.27 1.27)
				)
			)
		)
		(property "Value" ""
			(at 0 0 90)
			(layer "F.Fab")
			(effects
				(font
					(size 1.27 1.27)
				)
			)
		)
		(duplicate_pad_numbers_are_jumpers no)
		(fp_line
			(start 0.7874 -0.4064)
			(end 0.7874 0.4064)
			(stroke
				(width 0.1524)
				(type default)
			)
			(layer "F.SilkS")
		)
		(fp_line
			(start -0.7874 -0.4064)
			(end 0.7874 -0.4064)
			(stroke
				(width 0.1524)
				(type default)
			)
			(layer "F.SilkS")
		)
		(fp_line
			(start 0.7874 0.4064)
			(end -0.7874 0.4064)
			(stroke
				(width 0.1524)
				(type default)
			)
			(layer "F.SilkS")
		)
		(fp_line
			(start -0.7874 0.4064)
			(end -0.7874 -0.4064)
			(stroke
				(width 0.1524)
				(type default)
			)
			(layer "F.SilkS")
		)
		(fp_line
			(start -0.12065 -0.305054)
			(end -0.12065 -0.2794)
			(stroke
				(width 0.1)
				(type default)
			)
			(layer "F.Fab")
		)
		(fp_line
			(start -0.67945 -0.305054)
			(end -0.12065 -0.305054)
			(stroke
				(width 0.1)
				(type default)
			)
			(layer "F.Fab")
		)
		(fp_line
			(start 0.67945 -0.3048)
			(end 0.67945 0.3048)
			(stroke
				(width 0.1)
				(type default)
			)
			(layer "F.Fab")
		)
		(fp_line
			(start 0.12065 -0.3048)
			(end 0.67945 -0.3048)
			(stroke
				(width 0.1)
				(type default)
			)
			(layer "F.Fab")
		)
		(fp_line
			(start 0.12065 -0.2794)
			(end 0.12065 -0.3048)
			(stroke
				(width 0.1)
				(type default)
			)
			(layer "F.Fab")
		)
		(fp_line
			(start -0.12065 -0.2794)
			(end 0.12065 -0.2794)
			(stroke
				(width 0.1)
				(type default)
			)
			(layer "F.Fab")
		)
		(fp_line
			(start 0.120396 0.2794)
			(end -0.12065 0.2794)
			(stroke
				(width 0.1)
				(type default)
			)
			(layer "F.Fab")
		)
		(fp_line
			(start -0.12065 0.2794)
			(end -0.12065 0.3048)
			(stroke
				(width 0.1)
				(type default)
			)
			(layer "F.Fab")
		)
		(fp_line
			(start 0.67945 0.3048)
			(end 0.120396 0.3048)
			(stroke
				(width 0.1)
				(type default)
			)
			(layer "F.Fab")
		)
		(fp_line
			(start 0.120396 0.3048)
			(end 0.120396 0.2794)
			(stroke
				(width 0.1)
				(type default)
			)
			(layer "F.Fab")
		)
		(fp_line
			(start -0.12065 0.3048)
			(end -0.67945 0.3048)
			(stroke
				(width 0.1)
				(type default)
			)
			(layer "F.Fab")
		)
		(fp_line
			(start -0.67945 0.3048)
			(end -0.67945 -0.305054)
			(stroke
				(width 0.1)
				(type default)
			)
			(layer "F.Fab")
		)
		(pad "1" smd circle
			(at -0.40005 0 90)
			(size 0 0)
			(layers "F.Cu" "F.Mask" "F.Paste")
			(net "PVDDIO_P0")
		)
		(pad "2" smd circle
			(at 0.40005 0 90)
			(size 0 0)
			(layers "F.Cu" "F.Mask" "F.Paste")
			(net "GND")
		)
	)
)
